#ISCELL
  mstr_misc dns *
  *
#ISCELL
  mstr_symbols design_note *
  *
#ISCELL
  mstr_symbols intel_corp_bpage *
  *
#ISCELL
  mstr_standard offpage *
  page126_i11
#CELL
  mstr_discrete res *
  page126_i12
#CELL
  mstr_discrete fet_n *
  page126_i13
#ISCELL
  mstr_symbols gnd *
  page126_i14
#ISCELL
  mstr_symbols p3v3_stby *
  page126_i16
#ISCELL
  mstr_standard offpage *
  page126_i17
#CELL
  mstr_discrete res *
  page126_i20
#ISCELL
  mstr_standard offpage *
  page126_i21
#CELL
  mstr_discrete res *
  page126_i22
#CELL
  mstr_discrete res *
  page126_i23
#ISCELL
  mstr_symbols gnd *
  page126_i24
#ISCELL
  mstr_symbols p3v3_stby *
  page126_i25
#ISCELL
  mstr_standard offpage *
  page126_i26
#CELL
  mstr_discrete res *
  page126_i27
#ISCELL
  mstr_symbols gnd *
  page126_i5
#CELL
  mstr_discrete res *
  page126_i6
#ISCELL
  mstr_symbols p3v3_stby *
  page126_i7
#ISCELL
  mstr_standard offpage *
  page126_i8
#ISCELL
  mstr_symbols p3v3_stby *
  page126_i9
